# S9S_MB_2U (Grand Teton) — schematic netlist excerpt (pin names and nets, part order shuffled) for the footprints in the layout excerpt that follows; sources: Cadence DE-HDL packaged netlist, KiCad conversion of 03242023_DA0F0TMBIJ0_F0T_Motherboard_J_brd_V01_OCP.brd

PU28_P1_3  ISL99390FRZTR5935  ISL99390FRZ-TR5935 IC  pkg QFN21_6X5XB  page 286
  VOS  = PVCCIN_CPU1_VOS3
  AGND  = GND
  VCC  = PVCCIN_CPU1_VDD3
  PVCC  = PVCCIN_CPU1_PVCC
  PGND1  = GND
  GL1  = NC
  PGND2  = GND
  SW  = SW_PVCCIN_CPU1_SW3
  VIN1  = SW_P12V_PVCCIN_CPU1_FLT
  VIN2  = SW_P12V_PVCCIN_CPU1_FLT
  DNC  = NC
  PHASE  = SW_PVCCIN_CPU1_BOOTR3
  BOOT  = SW_PVCCIN_CPU1_BOOT3
  PWM  = PVCCIN_CPU1_PWM3
  EN  = PVCCIN_CPU1_VDD3
  TOUT_FLT  = PVCCIN_CPU1_ATSEN
  LSET  = PVCCIN_CPU1_LSET3
  IOUT  = PVCCIN_CPU1_IMON3
  REFIN  = PVCCIN_CPU1_VREF
  PGND3  = GND
  GL2  = NC

(kicad_pcb
	(version 20260206)
	(generator "pcbnew")
	(generator_version "10.0")
	(general
		(thickness 1.6)
		(legacy_teardrops no)
	)
	(paper "A4")
	(title_block
		(title "03242023_DA0F0TMBIJ0_F0T_Motherboard_J_brd_V01_OCP.brd")
		(comment 1 "Grand Teton / footprints 358-358 of 6105")
	)
	(layers
		(0 "F.Cu" signal "TOP")
		(4 "In1.Cu" signal "GND")
		(6 "In2.Cu" signal "IN1")
		(8 "In3.Cu" signal "GND1")
		(10 "In4.Cu" signal "IN2")
		(12 "In5.Cu" signal "GND2")
		(14 "In6.Cu" signal "IN3")
		(16 "In7.Cu" signal "GND3")
		(18 "In8.Cu" signal "VCC")
		(20 "In9.Cu" signal "VCC1")
		(22 "In10.Cu" signal "GND4")
		(24 "In11.Cu" signal "IN4")
		(26 "In12.Cu" signal "GND5")
		(28 "In13.Cu" signal "IN5")
		(30 "In14.Cu" signal "GND6")
		(32 "In15.Cu" signal "IN6")
		(34 "In16.Cu" signal "GND7")
		(2 "B.Cu" signal "BOTTOM")
		(9 "F.Adhes" user "F.Adhesive")
		(11 "B.Adhes" user "B.Adhesive")
		(13 "F.Paste" user "Package Geometry/Pastemask Top")
		(15 "B.Paste" user "Package Geometry/Pastemask Bottom")
		(5 "F.SilkS" user "Ref Des/Silkscreen Top")
		(7 "B.SilkS" user "Ref Des/Silkscreen Bottom")
		(1 "F.Mask" user "Board Geometry/Soldermask Top")
		(3 "B.Mask" user "Board Geometry/Soldermask Bottom")
		(17 "Dwgs.User" user "User.Drawings")
		(19 "Cmts.User" user "User.Comments")
		(21 "Eco1.User" user "User.Eco1")
		(23 "Eco2.User" user "User.Eco2")
		(25 "Edge.Cuts" user "Board Geometry/Outline")
		(27 "Margin" user)
		(31 "F.CrtYd" user "Package Geometry/Place Bound Top")
		(29 "B.CrtYd" user "Package Geometry/Place Bound Bottom")
		(35 "F.Fab" user "Ref Des/Assembly Top")
		(33 "B.Fab" user "Ref Des/Assembly Bottom")
	)
	(footprint ""
		(layer "F.Cu")
		(at 113.318798 -333.716122)
		(property "Reference" "PU28_P1_3"
			(at -1.810258 -6.183376 0)
			(unlocked yes)
			(layer "F.SilkS")
			(effects
				(font
					(size 0.7874 0.5842)
					(thickness 0.1524)
				)
				(justify left)
			)
		)
		(property "Value" ""
			(at 0 0 0)
			(layer "F.Fab")
			(effects
				(font
					(size 1.27 1.27)
				)
			)
		)
		(duplicate_pad_numbers_are_jumpers no)
		(fp_line
			(start -2.500122 -2.999994)
			(end -2.24409 -2.999994)
			(stroke
				(width 0.1524)
				(type default)
			)
			(layer "F.SilkS")
		)
		(fp_line
			(start -2.500122 -2.529078)
			(end -2.500122 -2.999994)
			(stroke
				(width 0.1524)
				(type default)
			)
			(layer "F.SilkS")
		)
		(fp_line
			(start -2.500122 0.6604)
			(end -2.500122 0.229108)
			(stroke
				(width 0.1524)
				(type default)
			)
			(layer "F.SilkS")
		)
		(fp_line
			(start -2.500122 2.999994)
			(end -2.500122 2.339594)
			(stroke
				(width 0.1524)
				(type default)
			)
			(layer "F.SilkS")
		)
		(fp_line
			(start -2.2987 2.999994)
			(end -2.500122 2.999994)
			(stroke
				(width 0.1524)
				(type default)
			)
			(layer "F.SilkS")
		)
		(fp_line
			(start 2.31394 -2.999994)
			(end 2.500122 -2.999994)
			(stroke
				(width 0.1524)
				(type default)
			)
			(layer "F.SilkS")
		)
		(fp_line
			(start 2.500122 -2.999994)
			(end 2.500122 -2.44348)
			(stroke
				(width 0.1524)
				(type default)
			)
			(layer "F.SilkS")
		)
		(fp_line
			(start 2.500122 2.339594)
			(end 2.500122 2.999994)
			(stroke
				(width 0.1524)
				(type default)
			)
			(layer "F.SilkS")
		)
		(fp_line
			(start 2.500122 2.999994)
			(end 2.2987 2.999994)
			(stroke
				(width 0.1524)
				(type default)
			)
			(layer "F.SilkS")
		)
		(fp_poly
			(pts
				(xy -2.148586 -3.63728) (xy -2.656586 -2.62128) (xy -3.164586 -3.63728)
			)
			(stroke
				(width 0)
				(type default)
			)
			(fill yes)
			(layer "F.SilkS")
		)
		(fp_line
			(start -2.500122 -2.999994)
			(end 2.500122 -2.999994)
			(stroke
				(width 0.1)
				(type default)
			)
			(layer "F.Fab")
		)
		(fp_line
			(start -2.500122 2.999994)
			(end -2.500122 -2.999994)
			(stroke
				(width 0.1)
				(type default)
			)
			(layer "F.Fab")
		)
		(fp_line
			(start 2.500122 -2.999994)
			(end 2.500122 2.999994)
			(stroke
				(width 0.1)
				(type default)
			)
			(layer "F.Fab")
		)
		(fp_line
			(start 2.500122 2.999994)
			(end -2.500122 2.999994)
			(stroke
				(width 0.1)
				(type default)
			)
			(layer "F.Fab")
		)
		(fp_poly
			(pts
				(xy -4.218432 -2.783078) (xy -4.218432 -1.767078) (xy -3.202432 -2.275078)
			)
			(stroke
				(width 0)
				(type default)
			)
			(fill yes)
			(layer "F.Fab")
		)
		(pad "1" smd rect
			(at -2.400046 -2.275078 90)
			(size 0.2286 0.6096)
			(layers "F.Cu" "F.Mask" "F.Paste")
			(net "PVCCIN_CPU1_VOS3")
		)
		(pad "2" smd rect
			(at -2.400046 -1.82499 90)
			(size 0.2286 0.6096)
			(layers "F.Cu" "F.Mask" "F.Paste")
			(net "GND")
		)
		(pad "3" smd rect
			(at -2.400046 -1.374902 90)
			(size 0.2286 0.6096)
			(layers "F.Cu" "F.Mask" "F.Paste")
			(net "PVCCIN_CPU1_VDD3")
		)
		(pad "4" smd rect
			(at -2.400046 -0.925068 90)
			(size 0.2286 0.6096)
			(layers "F.Cu" "F.Mask" "F.Paste")
			(net "PVCCIN_CPU1_PVCC")
		)
		(pad "5" smd rect
			(at -2.400046 -0.47498 90)
			(size 0.2286 0.6096)
			(layers "F.Cu" "F.Mask" "F.Paste")
			(net "GND")
		)
		(pad "6" smd rect
			(at -2.400046 -0.024892 90)
			(size 0.2286 0.6096)
			(layers "F.Cu" "F.Mask" "F.Paste")
			(net "Net_8526")
		)
		(pad "7_9-20_24" smd circle
			(at 0 1.150112 90)
			(size 0 0)
			(layers "F.Cu" "F.Mask" "F.Paste")
			(net "GND")
		)
		(pad "10_19" smd rect
			(at 0 2.899918 90)
			(size 0.6096 4.318)
			(layers "F.Cu" "F.Mask" "F.Paste")
			(net "SW_PVCCIN_CPU1_SW3")
		)
		(pad "25_29" smd rect
			(at 1.549908 -1.279906 270)
			(size 2.0574 2.3114)
			(layers "F.Cu" "F.Mask" "F.Paste")
			(net "SW_P12V_PVCCIN_CPU1_FLT")
		)
		(pad "30" smd rect
			(at 2.05994 -2.899918)
			(size 0.2286 0.6096)
			(layers "F.Cu" "F.Mask" "F.Paste")
			(net "SW_P12V_PVCCIN_CPU1_FLT")
		)
		(pad "31" smd rect
			(at 1.610106 -2.899918)
			(size 0.2286 0.6096)
			(layers "F.Cu" "F.Mask" "F.Paste")
			(net "Net_8527")
		)
		(pad "32" smd rect
			(at 1.160018 -2.899918)
			(size 0.2286 0.6096)
			(layers "F.Cu" "F.Mask" "F.Paste")
			(net "SW_PVCCIN_CPU1_BOOTR3")
		)
		(pad "33" smd rect
			(at 0.70993 -2.899918)
			(size 0.2286 0.6096)
			(layers "F.Cu" "F.Mask" "F.Paste")
			(net "SW_PVCCIN_CPU1_BOOT3")
		)
		(pad "34" smd rect
			(at 0.260096 -2.899918)
			(size 0.2286 0.6096)
			(layers "F.Cu" "F.Mask" "F.Paste")
			(net "PVCCIN_CPU1_PWM3")
		)
		(pad "35" smd rect
			(at -0.189992 -2.899918)
			(size 0.2286 0.6096)
			(layers "F.Cu" "F.Mask" "F.Paste")
			(net "PVCCIN_CPU1_VDD3")
		)
		(pad "36" smd rect
			(at -0.64008 -2.899918)
			(size 0.2286 0.6096)
			(layers "F.Cu" "F.Mask" "F.Paste")
			(net "PVCCIN_CPU1_ATSEN")
		)
		(pad "37" smd rect
			(at -1.089914 -2.899918)
			(size 0.2286 0.6096)
			(layers "F.Cu" "F.Mask" "F.Paste")
			(net "PVCCIN_CPU1_LSET3")
		)
		(pad "38" smd rect
			(at -1.540002 -2.899918)
			(size 0.2286 0.6096)
			(layers "F.Cu" "F.Mask" "F.Paste")
			(net "PVCCIN_CPU1_IMON3")
		)
		(pad "39" smd rect
			(at -1.99009 -2.899918)
			(size 0.2286 0.6096)
			(layers "F.Cu" "F.Mask" "F.Paste")
			(net "PVCCIN_CPU1_VREF")
		)
		(pad "40" smd rect
			(at -0.87503 -1.27508)
			(size 1.7526 1.9558)
			(layers "F.Cu" "F.Mask" "F.Paste")
			(net "GND")
		)
		(pad "41" smd rect
			(at -1.525016 0.249936 270)
			(size 0.3048 0.4572)
			(layers "F.Cu" "F.Mask" "F.Paste")
			(net "Net_8525")
		)
		(zone
			(layer "F.Cu")
			(hatch none 0.5)
			(connect_pads
				(clearance 0)
			)
			(min_thickness 0.25)
			(keepout
				(tracks not_allowed)
				(vias allowed)
				(pads allowed)
				(copperpour not_allowed)
				(footprints allowed)
			)
			(placement
				(enabled no)
				(sheetname "")
			)
			(fill
				(thermal_gap 0.5)
				(thermal_bridge_width 0.5)
				(island_removal_mode 0)
			)
			(polygon
				(pts
					(xy 110.818676 -330.716128) (xy 110.818676 -331.465428) (xy 115.81892 -331.465428) (xy 115.81892 -330.716128)
					(xy 115.528598 -330.716128) (xy 115.528598 -331.171804) (xy 111.108998 -331.171804) (xy 111.108998 -330.716128)
				)
			)
		)
		(zone
			(layer "F.Cu")
			(hatch none 0.5)
			(connect_pads
				(clearance 0)
			)
			(min_thickness 0.25)
			(keepout
				(tracks not_allowed)
				(vias allowed)
				(pads allowed)
				(copperpour not_allowed)
				(footprints allowed)
			)
			(placement
				(enabled no)
				(sheetname "")
			)
			(fill
				(thermal_gap 0.5)
				(thermal_bridge_width 0.5)
				(island_removal_mode 0)
			)
			(polygon
				(pts
					(xy 111.274352 -334.040988) (xy 111.516668 -334.040988) (xy 111.516668 -333.962502) (xy 112.3061 -333.962502)
					(xy 112.3061 -333.644748) (xy 112.368076 -333.644748) (xy 112.368076 -332.966822) (xy 110.818676 -332.966822)
					(xy 110.818676 -333.423514) (xy 111.514382 -333.423514) (xy 111.514382 -333.262986) (xy 112.073182 -333.262986)
					(xy 112.073182 -333.669386) (xy 111.514382 -333.669386) (xy 111.514382 -333.448914) (xy 110.818676 -333.448914)
					(xy 110.818676 -333.575914) (xy 111.274352 -333.575914)
				)
			)
		)
	)
)
